# T6G (Grand Teton) — schematic netlist excerpt (pin names and nets, part order shuffled) for the footprints in the layout excerpt that follows; sources: Cadence DE-HDL packaged netlist, KiCad conversion of 04192023_DAF0TMB3IC0_F0TG_MB_C_brd_V02_OCP.brd

C7035  Q_CAP  47UF 4V 20% X6S  pkg C0805  page 279 : A = P0V9_CPU0_RT_2D ; B = GND

X9003  TP_TDR_4P_FTS  TP_TDR_4P_DIP EMPTY  pkg TH  page 261
  S1  = TDR_DIFF_85_NECK_IN2_DP
  P1  = T1_GND
  P2  = T1_GND
  S2  = TDR_DIFF_85_NECK_IN2_DN

(kicad_pcb
	(version 20260206)
	(generator "pcbnew")
	(generator_version "10.0")
	(general
		(thickness 1.6)
		(legacy_teardrops no)
	)
	(paper "A4")
	(title_block
		(title "04192023_DAF0TMB3IC0_F0TG_MB_C_brd_V02_OCP.brd")
		(comment 1 "Grand Teton / footprints 849-850 of 8354")
	)
	(layers
		(0 "F.Cu" signal "TOP")
		(4 "In1.Cu" signal "GND")
		(6 "In2.Cu" signal "IN1")
		(8 "In3.Cu" signal "GND1")
		(10 "In4.Cu" signal "IN2")
		(12 "In5.Cu" signal "GND2")
		(14 "In6.Cu" signal "IN3")
		(16 "In7.Cu" signal "GND3")
		(18 "In8.Cu" signal "VCC")
		(20 "In9.Cu" signal "VCC1")
		(22 "In10.Cu" signal "GND4")
		(24 "In11.Cu" signal "IN4")
		(26 "In12.Cu" signal "GND5")
		(28 "In13.Cu" signal "IN5")
		(30 "In14.Cu" signal "GND6")
		(32 "In15.Cu" signal "IN6")
		(34 "In16.Cu" signal "GND7")
		(2 "B.Cu" signal "BOTTOM")
		(9 "F.Adhes" user "F.Adhesive")
		(11 "B.Adhes" user "B.Adhesive")
		(13 "F.Paste" user "Package Geometry/Pastemask Top")
		(15 "B.Paste" user "Package Geometry/Pastemask Bottom")
		(5 "F.SilkS" user "Ref Des/Silkscreen Top")
		(7 "B.SilkS" user "Ref Des/Silkscreen Bottom")
		(1 "F.Mask" user "Board Geometry/Soldermask Top")
		(3 "B.Mask" user "Board Geometry/Soldermask Bottom")
		(17 "Dwgs.User" user "User.Drawings")
		(19 "Cmts.User" user "User.Comments")
		(21 "Eco1.User" user "User.Eco1")
		(23 "Eco2.User" user "User.Eco2")
		(25 "Edge.Cuts" user "Board Geometry/Outline")
		(27 "Margin" user)
		(31 "F.CrtYd" user "Package Geometry/Place Bound Top")
		(29 "B.CrtYd" user "Package Geometry/Place Bound Bottom")
		(35 "F.Fab" user "Ref Des/Assembly Top")
		(33 "B.Fab" user "Ref Des/Assembly Bottom")
	)
	(footprint ""
		(layer "F.Cu")
		(at 330.938632 -410.251656 90)
		(property "Reference" "C7035"
			(at 0 0 90)
			(layer "F.SilkS")
			(hide yes)
			(effects
				(font
					(size 1.27 1.27)
				)
			)
		)
		(property "Value" ""
			(at 0 0 90)
			(layer "F.Fab")
			(effects
				(font
					(size 1.27 1.27)
				)
			)
		)
		(duplicate_pad_numbers_are_jumpers no)
		(fp_line
			(start 1.524 -0.762)
			(end 1.524 0.762)
			(stroke
				(width 0.1524)
				(type default)
			)
			(layer "F.SilkS")
		)
		(fp_line
			(start -1.524 -0.762)
			(end 1.524 -0.762)
			(stroke
				(width 0.1524)
				(type default)
			)
			(layer "F.SilkS")
		)
		(fp_line
			(start 1.524 0.762)
			(end -1.524 0.762)
			(stroke
				(width 0.1524)
				(type default)
			)
			(layer "F.SilkS")
		)
		(fp_line
			(start -1.524 0.762)
			(end -1.524 -0.762)
			(stroke
				(width 0.1524)
				(type default)
			)
			(layer "F.SilkS")
		)
		(fp_line
			(start 1.1049 -0.724916)
			(end -1.1049 -0.724916)
			(stroke
				(width 0.1)
				(type default)
			)
			(layer "F.Fab")
		)
		(fp_line
			(start -1.1049 -0.724916)
			(end -1.1049 0.724916)
			(stroke
				(width 0.1)
				(type default)
			)
			(layer "F.Fab")
		)
		(fp_line
			(start 1.1049 0.724916)
			(end 1.1049 -0.724916)
			(stroke
				(width 0.1)
				(type default)
			)
			(layer "F.Fab")
		)
		(fp_line
			(start -1.1049 0.724916)
			(end 1.1049 0.724916)
			(stroke
				(width 0.1)
				(type default)
			)
			(layer "F.Fab")
		)
		(pad "1" smd rect
			(at -0.889 0 270)
			(size 1.016 1.27)
			(layers "F.Cu" "F.Mask" "F.Paste")
			(net "P0V9_CPU0_RT_2D")
		)
		(pad "2" smd rect
			(at 0.889 0 270)
			(size 1.016 1.27)
			(layers "F.Cu" "F.Mask" "F.Paste")
			(net "GND")
		)
	)
	(footprint ""
		(layer "F.Cu")
		(at 495.525044 -306.87518 -90)
		(property "Reference" "X9003"
			(at -1.82372 4.797298 0)
			(unlocked yes)
			(layer "F.SilkS")
			(effects
				(font
					(size 0.7874 0.5842)
					(thickness 0.1524)
				)
				(justify left)
			)
		)
		(property "Value" ""
			(at 0 0 270)
			(layer "F.Fab")
			(effects
				(font
					(size 1.27 1.27)
				)
			)
		)
		(property "User Part Number" "N_A"
			(at 1.30175 1.27 0)
			(unlocked yes)
			(layer "Cmts.User")
			(hide yes)
			(effects
				(font
					(size 0.635 0.4064)
					(thickness 0.1524)
				)
			)
		)
		(property "Device Type" "TP_TDR_4P_FTS_TH-TP_TDR_4P_DIP,EMPTY,TP15"
			(at 1.30175 1.27 0)
			(unlocked yes)
			(layer "F.Fab")
			(hide yes)
			(effects
				(font
					(size 0.635 0.4064)
					(thickness 0.1524)
				)
			)
		)
		(duplicate_pad_numbers_are_jumpers no)
		(fp_line
			(start 0 3.81)
			(end 2.54 3.81)
			(stroke
				(width 0.1524)
				(type default)
			)
			(layer "F.SilkS")
		)
		(fp_line
			(start 2.54 3.81)
			(end 2.54 3.6703)
			(stroke
				(width 0.1524)
				(type default)
			)
			(layer "F.SilkS")
		)
		(fp_line
			(start 0 3.175)
			(end 0 3.81)
			(stroke
				(width 0.1524)
				(type default)
			)
			(layer "F.SilkS")
		)
		(fp_line
			(start 2.54 1.4097)
			(end 2.54 1.1303)
			(stroke
				(width 0.1524)
				(type default)
			)
			(layer "F.SilkS")
		)
		(fp_line
			(start 0 0.635)
			(end 0 1.905)
			(stroke
				(width 0.1524)
				(type default)
			)
			(layer "F.SilkS")
		)
		(fp_line
			(start 2.54 -1.1303)
			(end 2.54 -1.27)
			(stroke
				(width 0.1524)
				(type default)
			)
			(layer "F.SilkS")
		)
		(fp_line
			(start 0 -1.27)
			(end 0 -0.635)
			(stroke
				(width 0.1524)
				(type default)
			)
			(layer "F.SilkS")
		)
		(fp_line
			(start 2.54 -1.27)
			(end 0 -1.27)
			(stroke
				(width 0.1524)
				(type default)
			)
			(layer "F.SilkS")
		)
		(fp_poly
			(pts
				(xy -2.285746 -0.762) (xy -0.761746 0) (xy -2.285746 0.762)
			)
			(stroke
				(width 0)
				(type default)
			)
			(fill yes)
			(layer "F.SilkS")
		)
		(fp_line
			(start 0 3.81)
			(end 2.54 3.81)
			(stroke
				(width 0.1)
				(type default)
			)
			(layer "F.Fab")
		)
		(fp_line
			(start 2.54 3.81)
			(end 2.54 -1.27)
			(stroke
				(width 0.1)
				(type default)
			)
			(layer "F.Fab")
		)
		(fp_line
			(start 0 -1.27)
			(end 0 3.81)
			(stroke
				(width 0.1)
				(type default)
			)
			(layer "F.Fab")
		)
		(fp_line
			(start 2.54 -1.27)
			(end 0 -1.27)
			(stroke
				(width 0.1)
				(type default)
			)
			(layer "F.Fab")
		)
		(fp_poly
			(pts
				(xy -0.761746 0) (xy -2.285746 -0.762) (xy -2.285746 0.762)
			)
			(stroke
				(width 0)
				(type default)
			)
			(fill yes)
			(layer "F.Fab")
		)
		(pad "1" thru_hole circle
			(at 0 0 270)
			(size 1.0033 1.0033)
			(drill 0.249936)
			(layers "*.Cu" "*.Mask")
			(remove_unused_layers no)
			(net "TDR_DIFF_85_NECK_IN2_DP")
			(clearance 0.10795)
			(thermal_gap 0.10795)
			(padstack
				(mode front_inner_back)
				(layer "Inner"
					(shape circle)
					(size 0.8001 0.8001)
					(clearance 0.1524)
				)
				(layer "B.Cu"
					(shape circle)
					(size 1.0033 1.0033)
					(clearance 0.10795)
				)
			)
		)
		(pad "2" thru_hole circle
			(at 2.54 0 270)
			(size 1.9939 1.9939)
			(drill 0.249936)
			(layers "*.Cu" "*.Mask")
			(remove_unused_layers no)
			(net "T1_GND")
			(clearance 0.10795)
			(thermal_gap 0.10795)
			(padstack
				(mode front_inner_back)
				(layer "Inner"
					(shape circle)
					(size 0.8001 0.8001)
					(clearance 0.1524)
				)
				(layer "B.Cu"
					(shape circle)
					(size 1.9939 1.9939)
					(clearance 0.10795)
				)
			)
		)
		(pad "3" thru_hole circle
			(at 2.54 2.54 270)
			(size 1.9939 1.9939)
			(drill 0.249936)
			(layers "*.Cu" "*.Mask")
			(remove_unused_layers no)
			(net "T1_GND")
			(clearance 0.10795)
			(thermal_gap 0.10795)
			(padstack
				(mode front_inner_back)
				(layer "Inner"
					(shape circle)
					(size 0.8001 0.8001)
					(clearance 0.1524)
				)
				(layer "B.Cu"
					(shape circle)
					(size 1.9939 1.9939)
					(clearance 0.10795)
				)
			)
		)
		(pad "4" thru_hole circle
			(at 0 2.54 270)
			(size 1.0033 1.0033)
			(drill 0.249936)
			(layers "*.Cu" "*.Mask")
			(remove_unused_layers no)
			(net "TDR_DIFF_85_NECK_IN2_DN")
			(clearance 0.10795)
			(thermal_gap 0.10795)
			(padstack
				(mode front_inner_back)
				(layer "Inner"
					(shape circle)
					(size 0.8001 0.8001)
					(clearance 0.1524)
				)
				(layer "B.Cu"
					(shape circle)
					(size 1.0033 1.0033)
					(clearance 0.10795)
				)
			)
		)
	)
)
